# S9S_MB_2U (Grand Teton) — schematic netlist excerpt (pin names and nets, part order shuffled) for the footprints in the layout excerpt that follows; sources: Cadence DE-HDL packaged netlist, KiCad conversion of 03242023_DA0F0TMBIJ0_F0T_Motherboard_J_brd_V01_OCP.brd

U314  9ZXL0451EKILFT  IC  pkg VFQFPN32_TH_0-5_5X5XD  page 211
  \^ckpwrgd_pd#\  = FM_9ZXL045_DEV_EN
  VDDR  = P3V3_9ZXL045_VDDR
  DIF_IN  = CLK_100M_GPU_SWB_REF_DP
  \dif_in#\  = CLK_100M_GPU_SWB_REF_DN
  VSADR0_TRI  = CLK_9ZXL045_SADR0
  SMBDAT  = SMB_HOST_9ZXL045_3V3AUX_SDA
  SMBCLK  = SMB_HOST_9ZXL045_3V3AUX_SCL
  \fbout_nc#\  = NC_U314_FBOUT_N
  FBOUT_NC  = NC_U314_FBOUT
  NC0  = NC_U314_NC0
  NC1  = NC_U314_NC1
  VDD0  = P3V3_9ZXL045_VDD
  DIF0  = CLK_100M_SWB_R_DP
  \dif0#\  = CLK_100M_SWB_R_DN
  \voe0#\  = FM_9ZXL045_0_OE_N
  VDD1  = P3V3_9ZXL045_VDD
  NC2  = NC_U314_NC2
  \voe1#\  = FM_9ZXL045_1_OE_N
  DIF1  = CLK_100M_GPU_1_R_DP
  \dif1#\  = CLK_100M_GPU_1_R_DN
  VDD2  = P3V3_9ZXL045_VDD
  DIF2  = CLK_100M_GPU_2_R_DP
  \dif2#\  = CLK_100M_GPU_2_R_DN
  \voe2#\  = FM_9ZXL045_2_OE_N
  VDD3  = P3V3_9ZXL045_VDD
  \voe3#\  = FM_9ZXL045_3_OE_N
  DIF3  = TP_CLK_100M_BUF_DIF3_DP
  \dif3#\  = TP_CLK_100M_BUF_DIF3_DN
  VDD4  = P3V3_9ZXL045_VDD
  NC3  = NC_U314_NC3
  VDDA  = P3V3_9ZXL045_VDDA
  \^hibw_bypm_lobw#\  = CLK_9ZXL045_HIBW
  EPAD_GND  = GND

(kicad_pcb
	(version 20260206)
	(generator "pcbnew")
	(generator_version "10.0")
	(general
		(thickness 1.6)
		(legacy_teardrops no)
	)
	(paper "A4")
	(title_block
		(title "03242023_DA0F0TMBIJ0_F0T_Motherboard_J_brd_V01_OCP.brd")
		(comment 1 "Grand Teton / footprint 3707 of 6105 (U314), pads 1-33 of 33")
	)
	(layers
		(0 "F.Cu" signal "TOP")
		(4 "In1.Cu" signal "GND")
		(6 "In2.Cu" signal "IN1")
		(8 "In3.Cu" signal "GND1")
		(10 "In4.Cu" signal "IN2")
		(12 "In5.Cu" signal "GND2")
		(14 "In6.Cu" signal "IN3")
		(16 "In7.Cu" signal "GND3")
		(18 "In8.Cu" signal "VCC")
		(20 "In9.Cu" signal "VCC1")
		(22 "In10.Cu" signal "GND4")
		(24 "In11.Cu" signal "IN4")
		(26 "In12.Cu" signal "GND5")
		(28 "In13.Cu" signal "IN5")
		(30 "In14.Cu" signal "GND6")
		(32 "In15.Cu" signal "IN6")
		(34 "In16.Cu" signal "GND7")
		(2 "B.Cu" signal "BOTTOM")
		(9 "F.Adhes" user "F.Adhesive")
		(11 "B.Adhes" user "B.Adhesive")
		(13 "F.Paste" user "Package Geometry/Pastemask Top")
		(15 "B.Paste" user "Package Geometry/Pastemask Bottom")
		(5 "F.SilkS" user "Ref Des/Silkscreen Top")
		(7 "B.SilkS" user "Ref Des/Silkscreen Bottom")
		(1 "F.Mask" user "Board Geometry/Soldermask Top")
		(3 "B.Mask" user "Board Geometry/Soldermask Bottom")
		(17 "Dwgs.User" user "User.Drawings")
		(19 "Cmts.User" user "User.Comments")
		(21 "Eco1.User" user "User.Eco1")
		(23 "Eco2.User" user "User.Eco2")
		(25 "Edge.Cuts" user "Board Geometry/Outline")
		(27 "Margin" user)
		(31 "F.CrtYd" user "Package Geometry/Place Bound Top")
		(29 "B.CrtYd" user "Package Geometry/Place Bound Bottom")
		(35 "F.Fab" user "Ref Des/Assembly Top")
		(33 "B.Fab" user "Ref Des/Assembly Bottom")
	)
	(footprint ""
		(layer "F.Cu")
		(at 112.26546 -413.408368 180)
		(property "Reference" "U314"
			(at 3.34772 6.20903 0)
			(unlocked yes)
			(layer "F.SilkS")
			(effects
				(font
					(size 0.7874 0.5842)
					(thickness 0.1524)
				)
			)
		)
		(property "Value" ""
			(at 0 0 180)
			(layer "F.Fab")
			(effects
				(font
					(size 1.27 1.27)
				)
			)
		)
		(duplicate_pad_numbers_are_jumpers no)
		(pad "1" smd rect
			(at -2.3749 -1.75006 90)
			(size 0.254 0.5588)
			(layers "F.Cu" "F.Mask" "F.Paste")
			(net "FM_9ZXL045_DEV_EN")
		)
		(pad "2" smd rect
			(at -2.3749 -1.249934 90)
			(size 0.254 0.5588)
			(layers "F.Cu" "F.Mask" "F.Paste")
			(net "P3V3_9ZXL045_VDDR")
		)
		(pad "3" smd rect
			(at -2.3749 -0.750062 90)
			(size 0.254 0.5588)
			(layers "F.Cu" "F.Mask" "F.Paste")
			(net "CLK_100M_GPU_SWB_REF_DP")
		)
		(pad "4" smd rect
			(at -2.3749 -0.249936 90)
			(size 0.254 0.5588)
			(layers "F.Cu" "F.Mask" "F.Paste")
			(net "CLK_100M_GPU_SWB_REF_DN")
		)
		(pad "5" smd rect
			(at -2.3749 0.249936 90)
			(size 0.254 0.5588)
			(layers "F.Cu" "F.Mask" "F.Paste")
			(net "CLK_9ZXL045_SADR0")
		)
		(pad "6" smd rect
			(at -2.3749 0.750062 90)
			(size 0.254 0.5588)
			(layers "F.Cu" "F.Mask" "F.Paste")
			(net "SMB_HOST_9ZXL045_3V3AUX_SDA")
		)
		(pad "7" smd rect
			(at -2.3749 1.249934 90)
			(size 0.254 0.5588)
			(layers "F.Cu" "F.Mask" "F.Paste")
			(net "SMB_HOST_9ZXL045_3V3AUX_SCL")
		)
		(pad "8" smd rect
			(at -2.3749 1.75006 90)
			(size 0.254 0.5588)
			(layers "F.Cu" "F.Mask" "F.Paste")
			(net "NC_U314_FBOUT_N")
		)
		(pad "9" smd rect
			(at -1.75006 2.3749 180)
			(size 0.254 0.5588)
			(layers "F.Cu" "F.Mask" "F.Paste")
			(net "NC_U314_FBOUT")
		)
		(pad "10" smd rect
			(at -1.249934 2.3749 180)
			(size 0.254 0.5588)
			(layers "F.Cu" "F.Mask" "F.Paste")
			(net "NC_U314_NC0")
		)
		(pad "11" smd rect
			(at -0.750062 2.3749 180)
			(size 0.254 0.5588)
			(layers "F.Cu" "F.Mask" "F.Paste")
			(net "NC_U314_NC1")
		)
		(pad "12" smd rect
			(at -0.249936 2.3749 180)
			(size 0.254 0.5588)
			(layers "F.Cu" "F.Mask" "F.Paste")
			(net "P3V3_9ZXL045_VDD")
		)
		(pad "13" smd rect
			(at 0.249936 2.3749 180)
			(size 0.254 0.5588)
			(layers "F.Cu" "F.Mask" "F.Paste")
			(net "CLK_100M_SWB_R_DP")
		)
		(pad "14" smd rect
			(at 0.750062 2.3749 180)
			(size 0.254 0.5588)
			(layers "F.Cu" "F.Mask" "F.Paste")
			(net "CLK_100M_SWB_R_DN")
		)
		(pad "15" smd rect
			(at 1.249934 2.3749 180)
			(size 0.254 0.5588)
			(layers "F.Cu" "F.Mask" "F.Paste")
			(net "FM_9ZXL045_0_OE_N")
		)
		(pad "16" smd rect
			(at 1.75006 2.3749 180)
			(size 0.254 0.5588)
			(layers "F.Cu" "F.Mask" "F.Paste")
			(net "P3V3_9ZXL045_VDD")
		)
		(pad "17" smd rect
			(at 2.3749 1.75006 270)
			(size 0.254 0.5588)
			(layers "F.Cu" "F.Mask" "F.Paste")
			(net "NC_U314_NC2")
		)
		(pad "18" smd rect
			(at 2.3749 1.249934 270)
			(size 0.254 0.5588)
			(layers "F.Cu" "F.Mask" "F.Paste")
			(net "FM_9ZXL045_1_OE_N")
		)
		(pad "19" smd rect
			(at 2.3749 0.750062 270)
			(size 0.254 0.5588)
			(layers "F.Cu" "F.Mask" "F.Paste")
			(net "CLK_100M_GPU_1_R_DP")
		)
		(pad "20" smd rect
			(at 2.3749 0.249936 270)
			(size 0.254 0.5588)
			(layers "F.Cu" "F.Mask" "F.Paste")
			(net "CLK_100M_GPU_1_R_DN")
		)
		(pad "21" smd rect
			(at 2.3749 -0.249936 270)
			(size 0.254 0.5588)
			(layers "F.Cu" "F.Mask" "F.Paste")
			(net "P3V3_9ZXL045_VDD")
		)
		(pad "22" smd rect
			(at 2.3749 -0.750062 270)
			(size 0.254 0.5588)
			(layers "F.Cu" "F.Mask" "F.Paste")
			(net "CLK_100M_GPU_2_R_DP")
		)
		(pad "23" smd rect
			(at 2.3749 -1.249934 270)
			(size 0.254 0.5588)
			(layers "F.Cu" "F.Mask" "F.Paste")
			(net "CLK_100M_GPU_2_R_DN")
		)
		(pad "24" smd rect
			(at 2.3749 -1.75006 270)
			(size 0.254 0.5588)
			(layers "F.Cu" "F.Mask" "F.Paste")
			(net "FM_9ZXL045_2_OE_N")
		)
		(pad "25" smd rect
			(at 1.75006 -2.3749)
			(size 0.254 0.5588)
			(layers "F.Cu" "F.Mask" "F.Paste")
			(net "P3V3_9ZXL045_VDD")
		)
		(pad "26" smd rect
			(at 1.249934 -2.3749)
			(size 0.254 0.5588)
			(layers "F.Cu" "F.Mask" "F.Paste")
			(net "FM_9ZXL045_3_OE_N")
		)
		(pad "27" smd rect
			(at 0.750062 -2.3749)
			(size 0.254 0.5588)
			(layers "F.Cu" "F.Mask" "F.Paste")
			(net "TP_CLK_100M_BUF_DIF3_DP")
		)
		(pad "28" smd rect
			(at 0.249936 -2.3749)
			(size 0.254 0.5588)
			(layers "F.Cu" "F.Mask" "F.Paste")
			(net "TP_CLK_100M_BUF_DIF3_DN")
		)
		(pad "29" smd rect
			(at -0.249936 -2.3749)
			(size 0.254 0.5588)
			(layers "F.Cu" "F.Mask" "F.Paste")
			(net "P3V3_9ZXL045_VDD")
		)
		(pad "30" smd rect
			(at -0.750062 -2.3749)
			(size 0.254 0.5588)
			(layers "F.Cu" "F.Mask" "F.Paste")
			(net "NC_U314_NC3")
		)
		(pad "31" smd rect
			(at -1.249934 -2.3749)
			(size 0.254 0.5588)
			(layers "F.Cu" "F.Mask" "F.Paste")
			(net "P3V3_9ZXL045_VDDA")
		)
		(pad "32" smd rect
			(at -1.75006 -2.3749)
			(size 0.254 0.5588)
			(layers "F.Cu" "F.Mask" "F.Paste")
			(net "CLK_9ZXL045_HIBW")
		)
		(pad "33" smd rect
			(at 0 0 180)
			(size 3.1496 3.1496)
			(layers "F.Cu" "F.Mask" "F.Paste")
			(net "GND")
		)
	)
)
